# BASEBOARD_FAB2 (Tioga Pass) — schematic netlist excerpt (pin names and nets, part order shuffled) for the footprints in the layout excerpt that follows; sources: Cadence DE-HDL packaged netlist, KiCad conversion of Wiwynn_Tioga_Pass_MB.brd

C8G9  CAP  0.22UF 16V 10% X7R  pkg 0402  page 105 : A = P3E_CPU0_PE2_SS_TXP<0> ; B = P3E_CPU0_PE2_SS_C_TXP<0>
C9W19  CAP_A  22.0UF 4V 20% X6S  pkg 0603V  page 239 : A = P1V2_AUX_BMC ; B = GND
RT26  1R3F-GP  1%  pkg RCL_GP  page 203 : \1\ = VR_PVCCIN_CPU0_PHASE3_RC ; \2\ = GND

(kicad_pcb
	(version 20260206)
	(generator "pcbnew")
	(generator_version "10.0")
	(general
		(thickness 1.6)
		(legacy_teardrops no)
	)
	(paper "A4")
	(title_block
		(title "Wiwynn_Tioga_Pass_MB.brd")
		(comment 1 "Tioga Pass / footprints 1866-1868 of 4770")
	)
	(layers
		(0 "F.Cu" signal "TOP")
		(4 "In1.Cu" signal "L2GND")
		(6 "In2.Cu" signal "L3")
		(8 "In3.Cu" signal "L4GND")
		(10 "In4.Cu" signal "L5")
		(12 "In5.Cu" signal "L6GND")
		(14 "In6.Cu" signal "L7VCC")
		(16 "In7.Cu" signal "L8VCC")
		(18 "In8.Cu" signal "L9GND")
		(20 "In9.Cu" signal "L10")
		(22 "In10.Cu" signal "L11GND")
		(24 "In11.Cu" signal "L12")
		(26 "In12.Cu" signal "L13GND")
		(2 "B.Cu" signal "BOTTOM")
		(9 "F.Adhes" user "F.Adhesive")
		(11 "B.Adhes" user "B.Adhesive")
		(13 "F.Paste" user "Package Geometry/Pastemask Top")
		(15 "B.Paste" user "Package Geometry/Pastemask Bottom")
		(5 "F.SilkS" user "Ref Des/Silkscreen Top")
		(7 "B.SilkS" user "Ref Des/Silkscreen Bottom")
		(1 "F.Mask" user "Board Geometry/Soldermask Top")
		(3 "B.Mask" user "Board Geometry/Soldermask Bottom")
		(17 "Dwgs.User" user "User.Drawings")
		(19 "Cmts.User" user "User.Comments")
		(21 "Eco1.User" user "User.Eco1")
		(23 "Eco2.User" user "User.Eco2")
		(25 "Edge.Cuts" user "Board Geometry/Outline")
		(27 "Margin" user)
		(31 "F.CrtYd" user "Package Geometry/Place Bound Top")
		(29 "B.CrtYd" user "Package Geometry/Place Bound Bottom")
		(35 "F.Fab" user "Ref Des/Assembly Top")
		(33 "B.Fab" user "Ref Des/Assembly Bottom")
	)
	(footprint ""
		(layer "F.Cu")
		(at 202.079098 -69.316092 -90)
		(property "Reference" "RT26"
			(at 0 0 270)
			(layer "F.SilkS")
			(hide yes)
			(effects
				(font
					(size 1.27 1.27)
				)
			)
		)
		(property "Value" "*"
			(at -0.0254 -2.6289 270)
			(unlocked yes)
			(layer "F.Fab")
			(hide yes)
			(effects
				(font
					(size 1.27 1.016)
					(thickness 0.1524)
				)
			)
		)
		(property "Device Type" "1R3F-GP_RCL_GP-1R3F-GP,64.1R00A"
			(at -0.0254 -4.1529 270)
			(unlocked yes)
			(layer "F.Fab")
			(hide yes)
			(effects
				(font
					(size 1.27 1.016)
					(thickness 0.1524)
				)
			)
		)
		(duplicate_pad_numbers_are_jumpers no)
		(fp_line
			(start -0.4826 0)
			(end -0.2032 0)
			(stroke
				(width 0.2032)
				(type default)
			)
			(layer "F.SilkS")
		)
		(fp_line
			(start 0.2032 0)
			(end 0.4826 0)
			(stroke
				(width 0.2032)
				(type default)
			)
			(layer "F.SilkS")
		)
		(fp_rect
			(start -0.5842 1.3335)
			(end 0.5842 -1.3335)
			(stroke
				(width 0)
				(type default)
			)
			(fill no)
			(layer "F.CrtYd")
		)
		(fp_rect
			(start -0.5842 1.3335)
			(end 0.5842 -1.3335)
			(stroke
				(width 0)
				(type default)
			)
			(fill no)
			(layer "F.Fab")
		)
		(pad "1" smd custom
			(at 0 -0.762 270)
			(size 0.2159 0.2159)
			(layers "F.Cu" "F.Mask" "F.Paste")
			(net "VR_PVCCIN_CPU0_PHASE3_RC")
			(options
				(clearance outline)
				(anchor circle)
			)
			(primitives
				(gr_poly
					(pts
						(arc
							(start -0.3302 -0.4318)
							(mid -0.402042 -0.402042)
							(end -0.4318 -0.3302)
						)
						(arc
							(start -0.4318 0.3302)
							(mid -0.402042 0.402042)
							(end -0.3302 0.4318)
						)
						(arc
							(start 0.3302 0.4318)
							(mid 0.402042 0.402042)
							(end 0.4318 0.3302)
						)
						(arc
							(start 0.4318 -0.3302)
							(mid 0.402042 -0.402042)
							(end 0.3302 -0.4318)
						)
					)
					(width 0)
					(fill yes)
				)
			)
		)
		(pad "2" smd custom
			(at 0 0.762 270)
			(size 0.2159 0.2159)
			(layers "F.Cu" "F.Mask" "F.Paste")
			(net "GND")
			(options
				(clearance outline)
				(anchor circle)
			)
			(primitives
				(gr_poly
					(pts
						(arc
							(start -0.3302 -0.4318)
							(mid -0.402042 -0.402042)
							(end -0.4318 -0.3302)
						)
						(arc
							(start -0.4318 0.3302)
							(mid -0.402042 0.402042)
							(end -0.3302 0.4318)
						)
						(arc
							(start 0.3302 0.4318)
							(mid 0.402042 0.402042)
							(end 0.4318 0.3302)
						)
						(arc
							(start 0.4318 -0.3302)
							(mid 0.402042 -0.402042)
							(end 0.3302 -0.4318)
						)
					)
					(width 0)
					(fill yes)
				)
			)
		)
	)
	(footprint ""
		(layer "F.Cu")
		(at 409.928822 -11.436858)
		(property "Reference" "C8G9"
			(at 0 0 0)
			(layer "F.SilkS")
			(hide yes)
			(effects
				(font
					(size 1.27 1.27)
				)
			)
		)
		(property "Value" ""
			(at 0 0 0)
			(layer "F.Fab")
			(effects
				(font
					(size 1.27 1.27)
				)
			)
		)
		(duplicate_pad_numbers_are_jumpers no)
		(fp_rect
			(start -0.3048 0.9906)
			(end 0.3048 -0.1016)
			(stroke
				(width 0)
				(type default)
			)
			(fill no)
			(layer "F.CrtYd")
		)
		(fp_line
			(start -0.3048 -0.1016)
			(end -0.3048 0.9906)
			(stroke
				(width 0.1)
				(type default)
			)
			(layer "F.Fab")
		)
		(fp_line
			(start -0.3048 0.9906)
			(end 0.3048 0.9906)
			(stroke
				(width 0.1)
				(type default)
			)
			(layer "F.Fab")
		)
		(fp_line
			(start 0.3048 -0.1016)
			(end -0.3048 -0.1016)
			(stroke
				(width 0.1)
				(type default)
			)
			(layer "F.Fab")
		)
		(fp_line
			(start 0.3048 0.9906)
			(end 0.3048 -0.1016)
			(stroke
				(width 0.1)
				(type default)
			)
			(layer "F.Fab")
		)
		(pad "1" smd rect
			(at 0 0)
			(size 0.508 0.508)
			(layers "F.Cu" "F.Mask" "F.Paste")
			(net "P3E_CPU0_PE2_SS_TXP<0>")
		)
		(pad "2" smd rect
			(at 0 0.889)
			(size 0.508 0.508)
			(layers "F.Cu" "F.Mask" "F.Paste")
			(net "P3E_CPU0_PE2_SS_C_TXP<0>")
		)
		(zone
			(layer "F.Cu")
			(hatch none 0.5)
			(connect_pads
				(clearance 0)
			)
			(min_thickness 0.25)
			(keepout
				(tracks allowed)
				(vias not_allowed)
				(pads allowed)
				(copperpour not_allowed)
				(footprints allowed)
			)
			(placement
				(enabled no)
				(sheetname "")
			)
			(fill
				(thermal_gap 0.5)
				(thermal_bridge_width 0.5)
				(island_removal_mode 0)
			)
			(polygon
				(pts
					(xy 409.674822 -10.801858) (xy 410.182822 -10.801858) (xy 410.182822 -11.182858) (xy 409.674822 -11.182858)
				)
			)
		)
	)
	(footprint ""
		(layer "F.Cu")
		(at 467.90102 -35.052 -90)
		(property "Reference" "C9W19"
			(at 0.97536 0.76708 180)
			(unlocked yes)
			(layer "F.SilkS")
			(effects
				(font
					(size 0.4064 0.254)
					(thickness 0.1524)
				)
			)
		)
		(property "Value" ""
			(at 0 0 270)
			(layer "F.Fab")
			(effects
				(font
					(size 1.27 1.27)
				)
			)
		)
		(duplicate_pad_numbers_are_jumpers no)
		(fp_poly
			(pts
				(xy -0.4953 -0.2032) (xy 0.4953 -0.2032) (xy 0.4953 1.6002) (xy -0.4953 1.6002)
			)
			(stroke
				(width 0)
				(type default)
			)
			(fill no)
			(layer "F.CrtYd")
		)
		(fp_line
			(start -0.4953 1.6002)
			(end -0.4953 -0.2032)
			(stroke
				(width 0.1)
				(type default)
			)
			(layer "F.Fab")
		)
		(fp_line
			(start 0.4953 1.6002)
			(end -0.4953 1.6002)
			(stroke
				(width 0.1)
				(type default)
			)
			(layer "F.Fab")
		)
		(fp_line
			(start -0.4953 -0.2032)
			(end 0.4953 -0.2032)
			(stroke
				(width 0.1)
				(type default)
			)
			(layer "F.Fab")
		)
		(fp_line
			(start 0.4953 -0.2032)
			(end 0.4953 1.6002)
			(stroke
				(width 0.1)
				(type default)
			)
			(layer "F.Fab")
		)
		(pad "1" smd rect
			(at 0 0 270)
			(size 0.762 0.889)
			(layers "F.Cu" "F.Mask" "F.Paste")
			(net "P1V2_AUX_BMC")
		)
		(pad "2" smd rect
			(at 0 1.397 270)
			(size 0.762 0.889)
			(layers "F.Cu" "F.Mask" "F.Paste")
			(net "GND")
		)
		(zone
			(layer "F.Cu")
			(hatch none 0.5)
			(connect_pads
				(clearance 0)
			)
			(min_thickness 0.25)
			(keepout
				(tracks not_allowed)
				(vias allowed)
				(pads allowed)
				(copperpour not_allowed)
				(footprints allowed)
			)
			(placement
				(enabled no)
				(sheetname "")
			)
			(fill
				(thermal_gap 0.5)
				(thermal_bridge_width 0.5)
				(island_removal_mode 0)
			)
			(polygon
				(pts
					(xy 467.45652 -35.433) (xy 467.45652 -34.671) (xy 466.94852 -34.671) (xy 466.94852 -35.433)
				)
			)
		)
	)
)
